#ISCELL
  mstr_symbols cad_note *
  *
#ISCELL
  mstr_symbols intel_corp_bpage *
  *
#ISCELL
  mstr_symbols gnd *
  page95_i1
#CELL
  mstr_discrete fet_n *
  page95_i104
#ISCELL
  mstr_symbols gnd *
  page95_i105
#CELL
  mstr_discrete res *
  page95_i106
#ISCELL
  mstr_symbols p3v3 *
  page95_i107
#CELL
  mstr_discrete res *
  page95_i108
#ISCELL
  mstr_standard offpage *
  page95_i109
#ISCELL
  mstr_standard offpage *
  page95_i110
#CELL
  mstr_discrete fet_n_dual *
  page95_i111
#CELL
  mstr_discrete fet_n_dual *
  page95_i112
#CELL
  mstr_discrete fet_n_dual *
  page95_i113
#ISCELL
  mstr_symbols p3v3_stby *
  page95_i114
#CELL
  dev_discrete cap_a *
  page95_i115
#ISCELL
  mstr_symbols gnd *
  page95_i116
#CELL
  mstr_ttl ttl1g08 *
  page95_i117
#CELL
  mstr_ttl ttl1g08 *
  page95_i118
#CELL
  mstr_discrete fet_n *
  page95_i119
#ISCELL
  mstr_standard offpage *
  page95_i12
#ISCELL
  mstr_symbols gnd *
  page95_i120
#ISCELL
  mstr_standard offpage *
  page95_i121
#ISCELL
  mstr_standard offpage *
  page95_i13
#ISCELL
  mstr_standard offpage *
  page95_i14
#ISCELL
  mstr_standard offpage *
  page95_i18
#ISCELL
  mstr_standard offpage *
  page95_i19
#ISCELL
  mstr_standard offpage *
  page95_i22
#ISCELL
  mstr_symbols gnd *
  page95_i23
#ISCELL
  mstr_symbols gnd *
  page95_i26
#ISCELL
  mstr_symbols gnd *
  page95_i27
#CELL
  mstr_discrete fet_n_dual *
  page95_i28
#ISCELL
  mstr_symbols gnd *
  page95_i29
#ISCELL
  mstr_symbols gnd *
  page95_i30
#CELL
  mstr_discrete fet_n_dual *
  page95_i32
#CELL
  mstr_discrete fet_n_dual *
  page95_i33
#CELL
  mstr_discrete fet_n_dual *
  page95_i51
#CELL
  mstr_discrete fet_n_dual *
  page95_i52
#ISCELL
  mstr_standard offpage *
  page95_i58
#CELL
  mstr_discrete fet_n_dual *
  page95_i59
#ISCELL
  mstr_standard offpage *
  page95_i6
#ISCELL
  mstr_symbols gnd *
  page95_i60
#ISCELL
  mstr_symbols p3v3 *
  page95_i61
#CELL
  mstr_discrete res *
  page95_i62
#ISCELL
  mstr_symbols gnd *
  page95_i63
#ISCELL
  mstr_standard offpage *
  page95_i66
#ISCELL
  mstr_standard offpage *
  page95_i67
#ISCELL
  mstr_standard offpage *
  page95_i68
#CELL
  mstr_discrete fet_n_dual *
  page95_i69
#ISCELL
  mstr_symbols gnd *
  page95_i70
#ISCELL
  mstr_symbols p3v3 *
  page95_i71
#CELL
  mstr_discrete res *
  page95_i72
#ISCELL
  mstr_symbols gnd *
  page95_i73
#ISCELL
  mstr_standard offpage *
  page95_i76
#ISCELL
  mstr_standard offpage *
  page95_i77
#CELL
  dev_discrete cap_a *
  page95_i92
#ISCELL
  mstr_symbols gnd *
  page95_i94
#ISCELL
  mstr_symbols p3v3_stby *
  page95_i98
